# S9S_MB_2U (Grand Teton) — schematic netlist excerpt (pin names and nets, part order shuffled) for the footprints in the layout excerpt that follows; sources: Cadence DE-HDL packaged netlist, KiCad conversion of 03242023_DA0F0TMBIJ0_F0T_Motherboard_J_brd_V01_OCP.brd

R3029  Q_RES  4.7K 5% CHIP  pkg 0402LF  page 148 : A = P3V3_AUX ; B = FM_SMB_1_ALERT_GPU

(kicad_pcb
	(version 20260206)
	(generator "pcbnew")
	(generator_version "10.0")
	(general
		(thickness 1.6)
		(legacy_teardrops no)
	)
	(paper "A4")
	(title_block
		(title "03242023_DA0F0TMBIJ0_F0T_Motherboard_J_brd_V01_OCP.brd")
		(comment 1 "Grand Teton / footprints 2496-2496 of 6105")
	)
	(layers
		(0 "F.Cu" signal "TOP")
		(4 "In1.Cu" signal "GND")
		(6 "In2.Cu" signal "IN1")
		(8 "In3.Cu" signal "GND1")
		(10 "In4.Cu" signal "IN2")
		(12 "In5.Cu" signal "GND2")
		(14 "In6.Cu" signal "IN3")
		(16 "In7.Cu" signal "GND3")
		(18 "In8.Cu" signal "VCC")
		(20 "In9.Cu" signal "VCC1")
		(22 "In10.Cu" signal "GND4")
		(24 "In11.Cu" signal "IN4")
		(26 "In12.Cu" signal "GND5")
		(28 "In13.Cu" signal "IN5")
		(30 "In14.Cu" signal "GND6")
		(32 "In15.Cu" signal "IN6")
		(34 "In16.Cu" signal "GND7")
		(2 "B.Cu" signal "BOTTOM")
		(9 "F.Adhes" user "F.Adhesive")
		(11 "B.Adhes" user "B.Adhesive")
		(13 "F.Paste" user "Package Geometry/Pastemask Top")
		(15 "B.Paste" user "Package Geometry/Pastemask Bottom")
		(5 "F.SilkS" user "Ref Des/Silkscreen Top")
		(7 "B.SilkS" user "Ref Des/Silkscreen Bottom")
		(1 "F.Mask" user "Board Geometry/Soldermask Top")
		(3 "B.Mask" user "Board Geometry/Soldermask Bottom")
		(17 "Dwgs.User" user "User.Drawings")
		(19 "Cmts.User" user "User.Comments")
		(21 "Eco1.User" user "User.Eco1")
		(23 "Eco2.User" user "User.Eco2")
		(25 "Edge.Cuts" user "Board Geometry/Outline")
		(27 "Margin" user)
		(31 "F.CrtYd" user "Package Geometry/Place Bound Top")
		(29 "B.CrtYd" user "Package Geometry/Place Bound Bottom")
		(35 "F.Fab" user "Ref Des/Assembly Top")
		(33 "B.Fab" user "Ref Des/Assembly Bottom")
	)
	(footprint ""
		(layer "F.Cu")
		(at 116.71808 -393.937998 90)
		(property "Reference" "R3029"
			(at 0 0 90)
			(layer "F.SilkS")
			(hide yes)
			(effects
				(font
					(size 1.27 1.27)
				)
			)
		)
		(property "Value" ""
			(at 0 0 90)
			(layer "F.Fab")
			(effects
				(font
					(size 1.27 1.27)
				)
			)
		)
		(duplicate_pad_numbers_are_jumpers no)
		(fp_line
			(start 0.7874 -0.4064)
			(end 0.7874 0.4064)
			(stroke
				(width 0.1524)
				(type default)
			)
			(layer "F.SilkS")
		)
		(fp_line
			(start -0.7874 -0.4064)
			(end 0.7874 -0.4064)
			(stroke
				(width 0.1524)
				(type default)
			)
			(layer "F.SilkS")
		)
		(fp_line
			(start 0.7874 0.4064)
			(end -0.7874 0.4064)
			(stroke
				(width 0.1524)
				(type default)
			)
			(layer "F.SilkS")
		)
		(fp_line
			(start -0.7874 0.4064)
			(end -0.7874 -0.4064)
			(stroke
				(width 0.1524)
				(type default)
			)
			(layer "F.SilkS")
		)
		(fp_line
			(start -0.12065 -0.305054)
			(end -0.12065 -0.2794)
			(stroke
				(width 0.1)
				(type default)
			)
			(layer "F.Fab")
		)
		(fp_line
			(start -0.67945 -0.305054)
			(end -0.12065 -0.305054)
			(stroke
				(width 0.1)
				(type default)
			)
			(layer "F.Fab")
		)
		(fp_line
			(start 0.67945 -0.3048)
			(end 0.67945 0.3048)
			(stroke
				(width 0.1)
				(type default)
			)
			(layer "F.Fab")
		)
		(fp_line
			(start 0.12065 -0.3048)
			(end 0.67945 -0.3048)
			(stroke
				(width 0.1)
				(type default)
			)
			(layer "F.Fab")
		)
		(fp_line
			(start 0.12065 -0.2794)
			(end 0.12065 -0.3048)
			(stroke
				(width 0.1)
				(type default)
			)
			(layer "F.Fab")
		)
		(fp_line
			(start -0.12065 -0.2794)
			(end 0.12065 -0.2794)
			(stroke
				(width 0.1)
				(type default)
			)
			(layer "F.Fab")
		)
		(fp_line
			(start 0.120396 0.2794)
			(end -0.12065 0.2794)
			(stroke
				(width 0.1)
				(type default)
			)
			(layer "F.Fab")
		)
		(fp_line
			(start -0.12065 0.2794)
			(end -0.12065 0.3048)
			(stroke
				(width 0.1)
				(type default)
			)
			(layer "F.Fab")
		)
		(fp_line
			(start 0.67945 0.3048)
			(end 0.120396 0.3048)
			(stroke
				(width 0.1)
				(type default)
			)
			(layer "F.Fab")
		)
		(fp_line
			(start 0.120396 0.3048)
			(end 0.120396 0.2794)
			(stroke
				(width 0.1)
				(type default)
			)
			(layer "F.Fab")
		)
		(fp_line
			(start -0.12065 0.3048)
			(end -0.67945 0.3048)
			(stroke
				(width 0.1)
				(type default)
			)
			(layer "F.Fab")
		)
		(fp_line
			(start -0.67945 0.3048)
			(end -0.67945 -0.305054)
			(stroke
				(width 0.1)
				(type default)
			)
			(layer "F.Fab")
		)
		(pad "1" smd circle
			(at -0.40005 0 90)
			(size 0 0)
			(layers "F.Cu" "F.Mask" "F.Paste")
			(net "P3V3_AUX")
		)
		(pad "2" smd circle
			(at 0.40005 0 90)
			(size 0 0)
			(layers "F.Cu" "F.Mask" "F.Paste")
			(net "FM_SMB_1_ALERT_GPU")
		)
	)
)
